(kicad_pcb
	(version 20240108)
	(generator "pcbnew")
	(generator_version "8.0")
	(general
		(thickness 1.62)
		(legacy_teardrops no)
	)
	(paper "A4")
	(title_block
		(title "Jetson Orin Baseboard")
		(date "2025-03-12")
		(rev "1.3.4")
		(company "Antmicro Ltd")
		(comment 1 "www.antmicro.com")
		(comment 9 "footprints 361-361 of 677")
	)
	(layers
		(0 "F.Cu" signal)
		(1 "In1.Cu" signal)
		(2 "In2.Cu" signal)
		(3 "In3.Cu" signal)
		(4 "In4.Cu" jumper)
		(5 "In5.Cu" signal)
		(6 "In6.Cu" signal)
		(31 "B.Cu" signal)
		(32 "B.Adhes" user "B.Adhesive")
		(33 "F.Adhes" user "F.Adhesive")
		(34 "B.Paste" user)
		(35 "F.Paste" user)
		(36 "B.SilkS" user "B.Silkscreen")
		(37 "F.SilkS" user "F.Silkscreen")
		(38 "B.Mask" user)
		(39 "F.Mask" user)
		(40 "Dwgs.User" user "User.Drawings")
		(41 "Cmts.User" user "User.Comments")
		(42 "Eco1.User" user "User.Eco1")
		(43 "Eco2.User" user "User.Eco2")
		(44 "Edge.Cuts" user)
		(45 "Margin" user)
		(46 "B.CrtYd" user "B.Courtyard")
		(47 "F.CrtYd" user "F.Courtyard")
		(48 "B.Fab" user)
		(49 "F.Fab" user)
	)
	(footprint "antmicro-footprints:WQFN-42-1EP_3.5x9mm_P0.5mm"
		(layer "B.Cu")
		(at 91.32 91.95 180)
		(descr "WQFN, 42 Pin (http://www.ti.com/lit/ds/symlink/ts3l501e.pdf#page=23), generated with kicad-footprint-generator ipc_noLead_generator.py")
		(tags "WQFN NoLead")
		(property "Reference" "U36"
			(at 0 5.821 0)
			(layer "B.SilkS")
			(effects
				(font
					(size 0.7 0.7)
					(thickness 0.15)
				)
				(justify left bottom mirror)
			)
		)
		(property "Value" "TS3DV642RUARQ1"
			(at 0 -5.82 0)
			(layer "B.Fab")
			(effects
				(font
					(size 0.7 0.7)
					(thickness 0.15)
				)
				(justify left bottom mirror)
			)
		)
		(property "Footprint" "antmicro-footprints:WQFN-42-1EP_3.5x9mm_P0.5mm"
			(at 0 0 180)
			(layer "F.Fab")
			(hide yes)
			(effects
				(font
					(size 1.27 1.27)
					(thickness 0.15)
				)
			)
		)
		(property "Datasheet" "https://www.ti.com/lit/ds/symlink/ts3dv642-q1.pdf?ts=1676983005656&ref_url=https%253A%252F%252Fwww.ti.com%252Fproduct%252FTS3DV642-Q1"
			(at 0 0 180)
			(layer "F.Fab")
			(hide yes)
			(effects
				(font
					(size 1.27 1.27)
					(thickness 0.15)
				)
			)
		)
		(property "Description" "Special purpose interface switch"
			(at 0 0 180)
			(layer "F.Fab")
			(hide yes)
			(effects
				(font
					(size 1.27 1.27)
					(thickness 0.15)
				)
			)
		)
		(property "Author" "Antmicro"
			(at 182.64 183.9 0)
			(layer "B.Fab")
			(hide yes)
			(effects
				(font
					(size 1 1)
					(thickness 0.15)
				)
				(justify mirror)
			)
		)
		(property "License" "Apache-2.0"
			(at 182.64 183.9 0)
			(layer "B.Fab")
			(hide yes)
			(effects
				(font
					(size 1 1)
					(thickness 0.15)
				)
				(justify mirror)
			)
		)
		(property "MPN" "TS3DV642RUARQ1"
			(at 182.64 183.9 0)
			(layer "B.Fab")
			(hide yes)
			(effects
				(font
					(size 1 1)
					(thickness 0.15)
				)
				(justify mirror)
			)
		)
		(property "Manufacturer" "Texas Instruments"
			(at 182.64 183.9 0)
			(layer "B.Fab")
			(hide yes)
			(effects
				(font
					(size 1 1)
					(thickness 0.15)
				)
				(justify mirror)
			)
		)
		(sheetname "HDMI")
		(sheetfile "hdmi.kicad_sch")
		(attr smd)
		(fp_line
			(start 1.86 4.611)
			(end 1.134 4.611)
			(stroke
				(width 0.15)
				(type solid)
			)
			(layer "B.SilkS")
		)
		(fp_line
			(start 1.86 4.385)
			(end 1.86 4.611)
			(stroke
				(width 0.15)
				(type solid)
			)
			(layer "B.SilkS")
		)
		(fp_line
			(start 1.86 -4.384)
			(end 1.86 -4.61)
			(stroke
				(width 0.15)
				(type solid)
			)
			(layer "B.SilkS")
		)
		(fp_line
			(start 1.86 -4.61)
			(end 1.134 -4.61)
			(stroke
				(width 0.15)
				(type solid)
			)
			(layer "B.SilkS")
		)
		(fp_line
			(start -1.861 4.611)
			(end -1.135 4.611)
			(stroke
				(width 0.15)
				(type solid)
			)
			(layer "B.SilkS")
		)
		(fp_line
			(start -1.861 -4.384)
			(end -1.861 -4.61)
			(stroke
				(width 0.15)
				(type solid)
			)
			(layer "B.SilkS")
		)
		(fp_line
			(start -1.861 -4.61)
			(end -1.135 -4.61)
			(stroke
				(width 0.15)
				(type solid)
			)
			(layer "B.SilkS")
		)
		(fp_circle
			(center -2.68 4)
			(end -2.63 4)
			(stroke
				(width 0.15)
				(type solid)
			)
			(fill solid)
			(layer "B.SilkS")
		)
		(fp_rect
			(start -2.25 5)
			(end 2.249 -4.998)
			(stroke
				(width 0.05)
				(type solid)
			)
			(fill none)
			(layer "B.CrtYd")
		)
		(fp_line
			(start 1.749 4.5)
			(end -0.875 4.5)
			(stroke
				(width 0.15)
				(type solid)
			)
			(layer "B.Fab")
		)
		(fp_line
			(start 1.749 -4.498)
			(end 1.749 4.5)
			(stroke
				(width 0.15)
				(type solid)
			)
			(layer "B.Fab")
		)
		(fp_line
			(start -0.875 4.5)
			(end -1.75 3.625)
			(stroke
				(width 0.15)
				(type solid)
			)
			(layer "B.Fab")
		)
		(fp_line
			(start -1.75 3.625)
			(end -1.75 -4.498)
			(stroke
				(width 0.15)
				(type solid)
			)
			(layer "B.Fab")
		)
		(fp_line
			(start -1.75 -4.498)
			(end 1.749 -4.498)
			(stroke
				(width 0.15)
				(type solid)
			)
			(layer "B.Fab")
		)
		(fp_text user "License: Apache-2.0"
			(at -2.73 -9.02 0)
			(layer "B.Fab")
			(hide yes)
			(effects
				(font
					(size 0.7 0.7)
					(thickness 0.15)
				)
				(justify left bottom mirror)
			)
		)
		(fp_text user "${REFERENCE}"
			(at -2.73 -10.22 0)
			(layer "B.Fab")
			(hide yes)
			(effects
				(font
					(size 0.7 0.7)
					(thickness 0.15)
				)
				(justify left bottom mirror)
			)
		)
		(fp_text user "Author: Antmicro"
			(at -2.73 -7.82 0)
			(layer "B.Fab")
			(hide yes)
			(effects
				(font
					(size 0.7 0.7)
					(thickness 0.15)
				)
				(justify left bottom mirror)
			)
		)
		(pad "" smd roundrect
			(at -0.51 -3.24 180)
			(size 0.83 0.87)
			(layers "B.Paste")
			(roundrect_rratio 0.25)
		)
		(pad "" smd roundrect
			(at -0.51 -2.16 180)
			(size 0.83 0.87)
			(layers "B.Paste")
			(roundrect_rratio 0.25)
		)
		(pad "" smd roundrect
			(at -0.51 -1.08 180)
			(size 0.83 0.87)
			(layers "B.Paste")
			(roundrect_rratio 0.25)
		)
		(pad "" smd roundrect
			(at -0.51 0 180)
			(size 0.83 0.87)
			(layers "B.Paste")
			(roundrect_rratio 0.25)
		)
		(pad "" smd roundrect
			(at -0.51 1.081 180)
			(size 0.83 0.87)
			(layers "B.Paste")
			(roundrect_rratio 0.25)
		)
		(pad "" smd roundrect
			(at -0.51 2.161 180)
			(size 0.83 0.87)
			(layers "B.Paste")
			(roundrect_rratio 0.25)
		)
		(pad "" smd roundrect
			(at -0.51 3.242 180)
			(size 0.83 0.87)
			(layers "B.Paste")
			(roundrect_rratio 0.25)
		)
		(pad "" smd roundrect
			(at 0.508 -3.24 180)
			(size 0.83 0.87)
			(layers "B.Paste")
			(roundrect_rratio 0.25)
		)
		(pad "" smd roundrect
			(at 0.508 -2.16 180)
			(size 0.83 0.87)
			(layers "B.Paste")
			(roundrect_rratio 0.25)
		)
		(pad "" smd roundrect
			(at 0.508 -1.08 180)
			(size 0.83 0.87)
			(layers "B.Paste")
			(roundrect_rratio 0.25)
		)
		(pad "" smd roundrect
			(at 0.508 0 180)
			(size 0.83 0.87)
			(layers "B.Paste")
			(roundrect_rratio 0.25)
		)
		(pad "" smd roundrect
			(at 0.508 1.081 180)
			(size 0.83 0.87)
			(layers "B.Paste")
			(roundrect_rratio 0.25)
		)
		(pad "" smd roundrect
			(at 0.508 2.161 180)
			(size 0.83 0.87)
			(layers "B.Paste")
			(roundrect_rratio 0.25)
		)
		(pad "" smd roundrect
			(at 0.508 3.242 180)
			(size 0.83 0.87)
			(layers "B.Paste")
			(roundrect_rratio 0.25)
		)
		(pad "1" smd roundrect
			(at -1.688 4 180)
			(size 0.875 0.25)
			(layers "B.Cu" "B.Paste" "B.Mask")
			(roundrect_rratio 0.25)
			(net 87 "+3V3")
			(pinfunction "VCC")
			(pintype "power_in")
		)
		(pad "2" smd roundrect
			(at -1.688 3.5 180)
			(size 0.875 0.25)
			(layers "B.Cu" "B.Paste" "B.Mask")
			(roundrect_rratio 0.25)
			(net 678 "/HDMI/DP_MUX_EN")
			(pinfunction "EN")
			(pintype "input")
		)
		(pad "3" smd roundrect
			(at -1.688 3 180)
			(size 0.875 0.25)
			(layers "B.Cu" "B.Paste" "B.Mask")
			(roundrect_rratio 0.25)
			(net 429 "DP1_HDMI_AUX_P")
			(pinfunction "SCL/AUX+")
			(pintype "bidirectional")
		)
		(pad "4" smd roundrect
			(at -1.688 2.5 180)
			(size 0.875 0.25)
			(layers "B.Cu" "B.Paste" "B.Mask")
			(roundrect_rratio 0.25)
			(net 430 "DP1_HDMI_AUX_N")
			(pinfunction "SDA/AUX-")
			(pintype "bidirectional")
		)
		(pad "5" smd roundrect
			(at -1.688 2 180)
			(size 0.875 0.25)
			(layers "B.Cu" "B.Paste" "B.Mask")
			(roundrect_rratio 0.25)
			(net 665 "/HDMI/DP_MUX_D0+")
			(pinfunction "D0+")
			(pintype "bidirectional")
		)
		(pad "6" smd roundrect
			(at -1.688 1.5 180)
			(size 0.875 0.25)
			(layers "B.Cu" "B.Paste" "B.Mask")
			(roundrect_rratio 0.25)
			(net 556 "/HDMI/DP_MUX_D0-")
			(pinfunction "D0-")
			(pintype "bidirectional")
		)
		(pad "7" smd roundrect
			(at -1.688 1 180)
			(size 0.875 0.25)
			(layers "B.Cu" "B.Paste" "B.Mask")
			(roundrect_rratio 0.25)
			(net 666 "/HDMI/DP_MUX_D1+")
			(pinfunction "D1+")
			(pintype "bidirectional")
		)
		(pad "8" smd roundrect
			(at -1.688 0.5 180)
			(size 0.875 0.25)
			(layers "B.Cu" "B.Paste" "B.Mask")
			(roundrect_rratio 0.25)
			(net 663 "/HDMI/DP_MUX_D1-")
			(pinfunction "D1-")
			(pintype "bidirectional")
		)
		(pad "9" smd roundrect
			(at -1.688 0 180)
			(size 0.875 0.25)
			(layers "B.Cu" "B.Paste" "B.Mask")
			(roundrect_rratio 0.25)
			(net 720 "unconnected-(U36-NC-Pad9)")
			(pinfunction "NC")
			(pintype "no_connect")
		)
		(pad "10" smd roundrect
			(at -1.688 -0.5 180)
			(size 0.875 0.25)
			(layers "B.Cu" "B.Paste" "B.Mask")
			(roundrect_rratio 0.25)
			(net 667 "/HDMI/DP_MUX_D2+")
			(pinfunction "D2+")
			(pintype "bidirectional")
		)
		(pad "11" smd roundrect
			(at -1.688 -1 180)
			(size 0.875 0.25)
			(layers "B.Cu" "B.Paste" "B.Mask")
			(roundrect_rratio 0.25)
			(net 664 "/HDMI/DP_MUX_D2-")
			(pinfunction "D2-")
			(pintype "bidirectional")
		)
		(pad "12" smd roundrect
			(at -1.688 -1.5 180)
			(size 0.875 0.25)
			(layers "B.Cu" "B.Paste" "B.Mask")
			(roundrect_rratio 0.25)
			(net 700 "/HDMI/DP_MUX_D3+")
			(pinfunction "D3+")
			(pintype "bidirectional")
		)
		(pad "13" smd roundrect
			(at -1.688 -2 180)
			(size 0.875 0.25)
			(layers "B.Cu" "B.Paste" "B.Mask")
			(roundrect_rratio 0.25)
			(net 699 "/HDMI/DP_MUX_D3-")
			(pinfunction "D3-")
			(pintype "bidirectional")
		)
		(pad "14" smd roundrect
			(at -1.688 -2.5 180)
			(size 0.875 0.25)
			(layers "B.Cu" "B.Paste" "B.Mask")
			(roundrect_rratio 0.25)
			(net 622 "Net-(Q1-D)")
			(pinfunction "HPD")
			(pintype "bidirectional")
		)
		(pad "15" smd roundrect
			(at -1.688 -3 180)
			(size 0.875 0.25)
			(layers "B.Cu" "B.Paste" "B.Mask")
			(roundrect_rratio 0.25)
			(net 721 "unconnected-(U36-CEC-Pad15)")
			(pinfunction "CEC")
			(pintype "bidirectional+no_connect")
		)
		(pad "16" smd roundrect
			(at -1.688 -3.5 180)
			(size 0.875 0.25)
			(layers "B.Cu" "B.Paste" "B.Mask")
			(roundrect_rratio 0.25)
			(net 686 "Net-(U36-SEL1)")
			(pinfunction "SEL1")
			(pintype "input")
		)
		(pad "17" smd roundrect
			(at -1.688 -4 180)
			(size 0.875 0.25)
			(layers "B.Cu" "B.Paste" "B.Mask")
			(roundrect_rratio 0.25)
			(net 624 "Net-(Q3-D)")
			(pinfunction "SEL2")
			(pintype "input")
		)
		(pad "18" smd roundrect
			(at -0.75 -4.437 180)
			(size 0.25 0.875)
			(layers "B.Cu" "B.Paste" "B.Mask")
			(roundrect_rratio 0.25)
			(net 722 "unconnected-(U36-CEC_A-Pad18)")
			(pinfunction "CEC_A")
			(pintype "bidirectional+no_connect")
		)
		(pad "19" smd roundrect
			(at -0.25 -4.437 180)
			(size 0.25 0.875)
			(layers "B.Cu" "B.Paste" "B.Mask")
			(roundrect_rratio 0.25)
			(net 677 "USBC_HPD")
			(pinfunction "HPD_A")
			(pintype "bidirectional")
		)
		(pad "20" smd roundrect
			(at 0.25 -4.437 180)
			(size 0.25 0.875)
			(layers "B.Cu" "B.Paste" "B.Mask")
			(roundrect_rratio 0.25)
			(net 723 "unconnected-(U36-CEC_B-Pad20)")
			(pinfunction "CEC_B")
			(pintype "bidirectional+no_connect")
		)
		(pad "21" smd roundrect
			(at 0.75 -4.437 180)
			(size 0.25 0.875)
			(layers "B.Cu" "B.Paste" "B.Mask")
			(roundrect_rratio 0.25)
			(net 703 "/HDMI/HDMI_HPD")
			(pinfunction "HPD_B")
			(pintype "bidirectional")
		)
		(pad "22" smd roundrect
			(at 1.687 -4 180)
			(size 0.875 0.25)
			(layers "B.Cu" "B.Paste" "B.Mask")
			(roundrect_rratio 0.25)
			(net 486 "/HDMI/HDMI_D2_N")
			(pinfunction "D3-B")
			(pintype "bidirectional")
		)
		(pad "23" smd roundrect
			(at 1.687 -3.5 180)
			(size 0.875 0.25)
			(layers "B.Cu" "B.Paste" "B.Mask")
			(roundrect_rratio 0.25)
			(net 492 "/HDMI/HDMI_D2_P")
			(pinfunction "D3+B")
			(pintype "bidirectional")
		)
		(pad "24" smd roundrect
			(at 1.687 -3 180)
			(size 0.875 0.25)
			(layers "B.Cu" "B.Paste" "B.Mask")
			(roundrect_rratio 0.25)
			(net 487 "/HDMI/HDMI_D1_N")
			(pinfunction "D2-B")
			(pintype "bidirectional")
		)
		(pad "25" smd roundrect
			(at 1.687 -2.5 180)
			(size 0.875 0.25)
			(layers "B.Cu" "B.Paste" "B.Mask")
			(roundrect_rratio 0.25)
			(net 493 "/HDMI/HDMI_D1_P")
			(pinfunction "D2+B")
			(pintype "bidirectional")
		)
		(pad "26" smd roundrect
			(at 1.687 -2 180)
			(size 0.875 0.25)
			(layers "B.Cu" "B.Paste" "B.Mask")
			(roundrect_rratio 0.25)
			(net 488 "/HDMI/HDMI_D0_N")
			(pinfunction "D1-B")
			(pintype "bidirectional")
		)
		(pad "27" smd roundrect
			(at 1.687 -1.5 180)
			(size 0.875 0.25)
			(layers "B.Cu" "B.Paste" "B.Mask")
			(roundrect_rratio 0.25)
			(net 494 "/HDMI/HDMI_D0_P")
			(pinfunction "D1+B")
			(pintype "bidirectional")
		)
		(pad "28" smd roundrect
			(at 1.687 -1 180)
			(size 0.875 0.25)
			(layers "B.Cu" "B.Paste" "B.Mask")
			(roundrect_rratio 0.25)
			(net 489 "/HDMI/HDMI_CLK_N")
			(pinfunction "D0-B")
			(pintype "bidirectional")
		)
		(pad "29" smd roundrect
			(at 1.687 -0.5 180)
			(size 0.875 0.25)
			(layers "B.Cu" "B.Paste" "B.Mask")
			(roundrect_rratio 0.25)
			(net 495 "/HDMI/HDMI_CLK_P")
			(pinfunction "D0+B")
			(pintype "bidirectional")
		)
		(pad "30" smd roundrect
			(at 1.687 0 180)
			(size 0.875 0.25)
			(layers "B.Cu" "B.Paste" "B.Mask")
			(roundrect_rratio 0.25)
			(net 724 "unconnected-(U36-NC-Pad30)")
			(pinfunction "NC")
			(pintype "no_connect")
		)
		(pad "31" smd roundrect
			(at 1.687 0.5 180)
			(size 0.875 0.25)
			(layers "B.Cu" "B.Paste" "B.Mask")
			(roundrect_rratio 0.25)
			(net 26 "DP1_TXD0_N")
			(pinfunction "D3-A")
			(pintype "bidirectional")
		)
		(pad "32" smd roundrect
			(at 1.687 1 180)
			(size 0.875 0.25)
			(layers "B.Cu" "B.Paste" "B.Mask")
			(roundrect_rratio 0.25)
			(net 496 "DP1_TXD0_P")
			(pinfunction "D3+A")
			(pintype "bidirectional")
		)
		(pad "33" smd roundrect
			(at 1.687 1.5 180)
			(size 0.875 0.25)
			(layers "B.Cu" "B.Paste" "B.Mask")
			(roundrect_rratio 0.25)
			(net 490 "DP1_TXD1_N")
			(pinfunction "D2-A")
			(pintype "bidirectional")
		)
		(pad "34" smd roundrect
			(at 1.687 2 180)
			(size 0.875 0.25)
			(layers "B.Cu" "B.Paste" "B.Mask")
			(roundrect_rratio 0.25)
			(net 27 "DP1_TXD1_P")
			(pinfunction "D2+A")
			(pintype "bidirectional")
		)
		(pad "35" smd roundrect
			(at 1.687 2.5 180)
			(size 0.875 0.25)
			(layers "B.Cu" "B.Paste" "B.Mask")
			(roundrect_rratio 0.25)
			(net 491 "DP1_TXD2_N")
			(pinfunction "D1-A")
			(pintype "bidirectional")
		)
		(pad "36" smd roundrect
			(at 1.687 3 180)
			(size 0.875 0.25)
			(layers "B.Cu" "B.Paste" "B.Mask")
			(roundrect_rratio 0.25)
			(net 497 "DP1_TXD2_P")
			(pinfunction "D1+A")
			(pintype "bidirectional")
		)
		(pad "37" smd roundrect
			(at 1.687 3.5 180)
			(size 0.875 0.25)
			(layers "B.Cu" "B.Paste" "B.Mask")
			(roundrect_rratio 0.25)
			(net 28 "DP1_TXD3_N")
			(pinfunction "D0-A")
			(pintype "bidirectional")
		)
		(pad "38" smd roundrect
			(at 1.687 4 180)
			(size 0.875 0.25)
			(layers "B.Cu" "B.Paste" "B.Mask")
			(roundrect_rratio 0.25)
			(net 29 "DP1_TXD3_P")
			(pinfunction "D0+A")
			(pintype "bidirectional")
		)
		(pad "39" smd roundrect
			(at 0.75 4.438 180)
			(size 0.25 0.875)
			(layers "B.Cu" "B.Paste" "B.Mask")
			(roundrect_rratio 0.25)
			(net 680 "/HDMI/DP_MUX_AUX_A-")
			(pinfunction "SDA/AUX-_B")
			(pintype "bidirectional")
		)
		(pad "40" smd roundrect
			(at 0.25 4.438 180)
			(size 0.25 0.875)
			(layers "B.Cu" "B.Paste" "B.Mask")
			(roundrect_rratio 0.25)
			(net 679 "/HDMI/DP_MUX_AUX_A+")
			(pinfunction "SCL/AUX+_B")
			(pintype "bidirectional")
		)
		(pad "41" smd roundrect
			(at -0.25 4.438 180)
			(size 0.25 0.875)
			(layers "B.Cu" "B.Paste" "B.Mask")
			(roundrect_rratio 0.25)
			(net 668 "/HDMI/DP_MUX_AUX_B-")
			(pinfunction "SDA/AUX-_A")
			(pintype "bidirectional")
		)
		(pad "42" smd roundrect
			(at -0.75 4.438 180)
			(size 0.25 0.875)
			(layers "B.Cu" "B.Paste" "B.Mask")
			(roundrect_rratio 0.25)
			(net 669 "/HDMI/DP_MUX_AUX_B+")
			(pinfunction "SCL/AUX+_A")
			(pintype "bidirectional")
		)
		(pad "43" smd rect
			(at 0 0 180)
			(size 2.05 7.55)
			(layers "B.Cu" "B.Mask")
			(net 1 "GND")
			(pinfunction "GND")
			(pintype "power_in")
		)
	)
)
